FILE_TYPE=LIBRARY_PARTS;
primitive 'PCA9555PWRG4-GP';
  pin
    'INT#':
      PIN_NUMBER='(1)';
      OUTPUT_LOAD='(1.0,-1.0)';
    'A1':
      PIN_NUMBER='(2)';
      INPUT_LOAD='(-0.01,0.01)';
    'A2':
      PIN_NUMBER='(3)';
      INPUT_LOAD='(-0.01,0.01)';
    'P0':
      PIN_NUMBER='(4)';
      BIDIRECTIONAL='TRUE';
      INPUT_LOAD='(-0.01,0.01)';
      OUTPUT_LOAD='(1.0,-1.0)';
    'P1':
      PIN_NUMBER='(5)';
      BIDIRECTIONAL='TRUE';
      INPUT_LOAD='(-0.01,0.01)';
      OUTPUT_LOAD='(1.0,-1.0)';
    'P2':
      PIN_NUMBER='(6)';
      BIDIRECTIONAL='TRUE';
      INPUT_LOAD='(-0.01,0.01)';
      OUTPUT_LOAD='(1.0,-1.0)';
    'P3':
      PIN_NUMBER='(7)';
      BIDIRECTIONAL='TRUE';
      INPUT_LOAD='(-0.01,0.01)';
      OUTPUT_LOAD='(1.0,-1.0)';
    'P4':
      PIN_NUMBER='(8)';
      BIDIRECTIONAL='TRUE';
      INPUT_LOAD='(-0.01,0.01)';
      OUTPUT_LOAD='(1.0,-1.0)';
    'P5':
      PIN_NUMBER='(9)';
      BIDIRECTIONAL='TRUE';
      INPUT_LOAD='(-0.01,0.01)';
      OUTPUT_LOAD='(1.0,-1.0)';
    'P6':
      PIN_NUMBER='(10)';
      BIDIRECTIONAL='TRUE';
      INPUT_LOAD='(-0.01,0.01)';
      OUTPUT_LOAD='(1.0,-1.0)';
    'P7':
      PIN_NUMBER='(11)';
      BIDIRECTIONAL='TRUE';
      INPUT_LOAD='(-0.01,0.01)';
      OUTPUT_LOAD='(1.0,-1.0)';
    'GND':
      PIN_NUMBER='(12)';
      PINUSE='POWER';
      NO_LOAD_CHECK='Both';
      NO_IO_CHECK='Both';
      NO_ASSERT_CHECK='TRUE';
      NO_DIR_CHECK='TRUE';
      ALLOW_CONNECT='TRUE';
    'P10':
      PIN_NUMBER='(13)';
      BIDIRECTIONAL='TRUE';
      INPUT_LOAD='(-0.01,0.01)';
      OUTPUT_LOAD='(1.0,-1.0)';
    'P11':
      PIN_NUMBER='(14)';
      BIDIRECTIONAL='TRUE';
      INPUT_LOAD='(-0.01,0.01)';
      OUTPUT_LOAD='(1.0,-1.0)';
    'P12':
      PIN_NUMBER='(15)';
      BIDIRECTIONAL='TRUE';
      INPUT_LOAD='(-0.01,0.01)';
      OUTPUT_LOAD='(1.0,-1.0)';
    'P13':
      PIN_NUMBER='(16)';
      BIDIRECTIONAL='TRUE';
      INPUT_LOAD='(-0.01,0.01)';
      OUTPUT_LOAD='(1.0,-1.0)';
    'P14':
      PIN_NUMBER='(17)';
      BIDIRECTIONAL='TRUE';
      INPUT_LOAD='(-0.01,0.01)';
      OUTPUT_LOAD='(1.0,-1.0)';
    'P15':
      PIN_NUMBER='(18)';
      BIDIRECTIONAL='TRUE';
      INPUT_LOAD='(-0.01,0.01)';
      OUTPUT_LOAD='(1.0,-1.0)';
    'P16':
      PIN_NUMBER='(19)';
      BIDIRECTIONAL='TRUE';
      INPUT_LOAD='(-0.01,0.01)';
      OUTPUT_LOAD='(1.0,-1.0)';
    'P17':
      PIN_NUMBER='(20)';
      BIDIRECTIONAL='TRUE';
      INPUT_LOAD='(-0.01,0.01)';
      OUTPUT_LOAD='(1.0,-1.0)';
    'A0':
      PIN_NUMBER='(21)';
      INPUT_LOAD='(-0.01,0.01)';
    'SCL':
      PIN_NUMBER='(22)';
      PIN_TYPE='ANALOG';
      NO_LOAD_CHECK='Both';
      NO_IO_CHECK='Both';
      NO_ASSERT_CHECK='TRUE';
      NO_DIR_CHECK='TRUE';
      ALLOW_CONNECT='TRUE';
    'SDA':
      PIN_NUMBER='(23)';
      PIN_TYPE='ANALOG';
      NO_LOAD_CHECK='Both';
      NO_IO_CHECK='Both';
      NO_ASSERT_CHECK='TRUE';
      NO_DIR_CHECK='TRUE';
      ALLOW_CONNECT='TRUE';
    'VCC':
      PIN_NUMBER='(24)';
      PINUSE='POWER';
      NO_LOAD_CHECK='Both';
      NO_IO_CHECK='Both';
      NO_ASSERT_CHECK='TRUE';
      NO_DIR_CHECK='TRUE';
      ALLOW_CONNECT='TRUE';
  end_pin;
  body
    PART_NAME='PCA9555PWRG4-GP';
    BODY_NAME='PCA9555PWRG4-GP';
    PHYS_DES_PREFIX='U';
    CLASS='IC';
  end_body;
end_primitive;

END.
